# S9S_MB_2U (Grand Teton) — schematic netlist excerpt (pin names and nets, part order shuffled) for the footprints in the layout excerpt that follows; sources: Cadence DE-HDL packaged netlist, KiCad conversion of 03242023_DA0F0TMBIJ0_F0T_Motherboard_J_brd_V01_OCP.brd

J5  SCONN288_ADR50017P130CC  SCONN288_ADR50017-P130CC IO  pkg DDR288S_1-1VXB  page 86
  VIN_BULK0  = P12V_S3_AUX_CPU0_NVDIMM
  RFU0  = TP_CHC_CPU0_DIMM1_FRU_0
  VIN_MGMT  = P3V3_AUX
  HSCL  = I3C_SPD_DDRABCD_CPU0_LVC1_SCL_4
  HSDA  = I3C_SPD_DDRABCD_CPU0_LVC1_SDA
  VSS0  = GND
  DQ0_A  = M_C_CPU0_SA_DQ<0>
  VSS1  = GND
  DQ1_A  = M_C_CPU0_SA_DQ<1>
  VSS2  = GND
  DQS0_A_T  = M_C_CPU0_SA_DQS_DP<0>
  DQS0_A_C  = M_C_CPU0_SA_DQS_DN<0>
  VSS3  = GND
  DQ4_A  = M_C_CPU0_SA_DQ<4>
  VSS4  = GND
  DQ5_A  = M_C_CPU0_SA_DQ<5>
  VSS5  = GND
  DQ8_A  = M_C_CPU0_SA_DQ<8>
  VSS6  = GND
  DQ9_A  = M_C_CPU0_SA_DQ<9>
  VSS7  = GND
  DQS1_A_T  = M_C_CPU0_SA_DQS_DP<1>
  DQS1_A_C  = M_C_CPU0_SA_DQS_DN<1>
  VSS8  = GND
  DQ12_A  = M_C_CPU0_SA_DQ<12>
  VSS9  = GND
  DQ13_A  = M_C_CPU0_SA_DQ<13>
  VSS10  = GND
  DQ16_A  = M_C_CPU0_SA_DQ<16>
  VSS11  = GND
  DQ17_A  = M_C_CPU0_SA_DQ<17>
  VSS12  = GND
  DQS2_A_T  = M_C_CPU0_SA_DQS_DP<2>
  DQS2_A_C  = M_C_CPU0_SA_DQS_DN<2>
  VSS13  = GND
  DQ20_A  = M_C_CPU0_SA_DQ<20>
  VSS14  = GND
  DQ21_A  = M_C_CPU0_SA_DQ<21>
  VSS15  = GND
  DQ24_A  = M_C_CPU0_SA_DQ<24>
  VSS16  = GND
  DQ25_A  = M_C_CPU0_SA_DQ<25>
  VSS17  = GND
  DQS3_A_T  = M_C_CPU0_SA_DQS_DP<3>
  DQS3_A_C  = M_C_CPU0_SA_DQS_DN<3>
  VSS18  = GND
  DQ28_A  = M_C_CPU0_SA_DQ<28>
  VSS19  = GND
  DQ29_A  = M_C_CPU0_SA_DQ<29>
  VSS20  = GND
  CB0_A  = M_C_CPU0_SA_CB<0>
  VSS21  = GND
  CB1_A  = M_C_CPU0_SA_CB<1>
  VSS22  = GND
  DQS4_A_T  = M_C_CPU0_SA_DQS_DP<4>
  DQS4_A_C  = M_C_CPU0_SA_DQS_DN<4>
  VSS23  = GND
  CB4_A  = M_C_CPU0_SA_CB<4>
  VSS24  = GND
  CB5_A  = M_C_CPU0_SA_CB<5>
  VSS25  = GND
  ALERT_N  = M_C_CPU0_ALERT_N
  VSS26  = GND
  CS0_A_N  = M_C_CPU0_SA_CS_N<0>
  VSS27  = GND
  CA0_A  = M_C_CPU0_SA_CA<0>
  VSS28  = GND
  CA2_A  = M_C_CPU0_SA_CA<2>
  VSS29  = GND
  CA4_A  = M_C_CPU0_SA_CA<4>
  VSS30  = GND
  CA6_A  = M_C_CPU0_SA_CA<6>
  VSS31  = GND
  PAR_A  = M_C_CPU0_SA_PAR
  VSS32  = GND
  CA0_B  = M_C_CPU0_SB_CA<0>
  VSS33  = GND
  CA2_B  = M_C_CPU0_SB_CA<2>
  VSS34  = GND
  CA4_B  = M_C_CPU0_SB_CA<4>
  VSS35  = GND
  CA6_B  = M_C_CPU0_SB_CA<6>
  VSS36  = GND
  CS0_B_N  = M_C_CPU0_SB_CS_N<0>
  VSS37  = GND
  \lbd||rsp_a_n\  = M_C_CPU0_SA_RSP<0>
  \lbs||rsp_b_n\  = M_C_CPU0_SB_RSP<0>
  VSS38  = GND
  CB4_B  = M_C_CPU0_SB_CB<4>
  VSS39  = GND
  CB5_B  = M_C_CPU0_SB_CB<5>
  VSS40  = GND
  \dqs9_b_t||tdqs9_b_t||dbi4_b_n\  = M_C_CPU0_SB_DQS_DP<9>
  \dqs9_b_c||tdqs9_b_c\  = M_C_CPU0_SB_DQS_DN<9>
  VSS41  = GND
  CB0_B  = M_C_CPU0_SB_CB<0>
  VSS42  = GND
  CB1_B  = M_C_CPU0_SB_CB<1>
  VSS43  = GND
  DQ0_B  = M_C_CPU0_SB_DQ<0>
  VSS44  = GND
  DQ1_B  = M_C_CPU0_SB_DQ<1>
  VSS45  = GND
  DQS0_B_T  = M_C_CPU0_SB_DQS_DP<0>
  DQS0_B_C  = M_C_CPU0_SB_DQS_DN<0>
  VSS46  = GND
  DQ4_B  = M_C_CPU0_SB_DQ<4>
  VSS47  = GND
  DQ5_B  = M_C_CPU0_SB_DQ<5>
  VSS48  = GND
  DQ8_B  = M_C_CPU0_SB_DQ<8>
  VSS49  = GND
  DQ9_B  = M_C_CPU0_SB_DQ<9>
  VSS50  = GND
  DQS1_B_T  = M_C_CPU0_SB_DQS_DP<1>
  DQS1_B_C  = M_C_CPU0_SB_DQS_DN<1>
  VSS51  = GND
  DQ12_B  = M_C_CPU0_SB_DQ<12>
  VSS52  = GND
  DQ13_B  = M_C_CPU0_SB_DQ<13>
  VSS53  = GND
  DQ16_B  = M_C_CPU0_SB_DQ<16>
  VSS54  = GND
  DQ17_B  = M_C_CPU0_SB_DQ<17>
  VSS55  = GND
  DQS2_B_T  = M_C_CPU0_SB_DQS_DP<2>
  DQS2_B_C  = M_C_CPU0_SB_DQS_DN<2>
  VSS56  = GND
  DQ20_B  = M_C_CPU0_SB_DQ<20>
  VSS57  = GND
  DQ21_B  = M_C_CPU0_SB_DQ<21>
  VSS58  = GND
  DQ24_B  = M_C_CPU0_SB_DQ<24>
  VSS59  = GND
  DQ25_B  = M_C_CPU0_SB_DQ<25>
  VSS60  = GND
  DQS3_B_T  = M_C_CPU0_SB_DQS_DP<3>
  DQS3_B_C  = M_C_CPU0_SB_DQS_DN<3>
  VSS61  = GND
  DQ28_B  = M_C_CPU0_SB_DQ<28>
  VSS62  = GND
  DQ29_B  = M_C_CPU0_SB_DQ<29>
  VSS63  = GND
  RFU1  = TP_CHC_CPU0_DIMM1_FRU_1
  VIN_BULK1  = P12V_S3_AUX_CPU0_NVDIMM
  VIN_BULK2  = P12V_S3_AUX_CPU0_NVDIMM
  \pwr_good||fail_n\  = PWRGD_CHC_CPU0_DIMM1
  HSA  = PD_CHC_CPU0_DIMM1_SAA
  RFU2  = TP_CHC_CPU0_DIMM1_FRU_2
  RFU3  = TP_CHC_CPU0_DIMM1_FRU_3
  VSS64  = GND
  DQ2_A  = M_C_CPU0_SA_DQ<2>
  VSS65  = GND
  DQ3_A  = M_C_CPU0_SA_DQ<3>
  VSS66  = GND
  \dqs5_a_c||tdqs5_a_c||dqs5_a_t||tdqs5_a_t\  = M_C_CPU0_SA_DQS_DN<5>
  \dqs5_a_t||tdqs5_a_t\  = M_C_CPU0_SA_DQS_DP<5>
  VSS67  = GND
  DQ6_A  = M_C_CPU0_SA_DQ<6>
  VSS68  = GND
  DQ7_A  = M_C_CPU0_SA_DQ<7>
  VSS69  = GND
  DQ10_A  = M_C_CPU0_SA_DQ<10>
  VSS70  = GND
  DQ11_A  = M_C_CPU0_SA_DQ<11>
  VSS71  = GND
  \dqs6_a_c||tdqs6_a_c||dqs6_a_t||tdqs6_a_t\  = M_C_CPU0_SA_DQS_DN<6>
  \dqs6_a_t||tdqs6_a_t\  = M_C_CPU0_SA_DQS_DP<6>
  VSS72  = GND
  DQ14_A  = M_C_CPU0_SA_DQ<14>
  VSS73  = GND
  DQ15_A  = M_C_CPU0_SA_DQ<15>
  VSS74  = GND
  DQ18_A  = M_C_CPU0_SA_DQ<18>
  VSS75  = GND
  DQ19_A  = M_C_CPU0_SA_DQ<19>
  VSS76  = GND
  \dqs7_a_c||tdqs7_a_c\  = M_C_CPU0_SA_DQS_DN<7>
  \dqs7_a_t||tdqs7_a_t\  = M_C_CPU0_SA_DQS_DP<7>
  VSS77  = GND
  DQ22_A  = M_C_CPU0_SA_DQ<22>
  VSS78  = GND
  DQ23_A  = M_C_CPU0_SA_DQ<23>
  VSS79  = GND
  DQ26_A  = M_C_CPU0_SA_DQ<26>
  VSS80  = GND
  DQ27_A  = M_C_CPU0_SA_DQ<27>
  VSS81  = GND
  \dqs8_a_c||tdqs8_a_c\  = M_C_CPU0_SA_DQS_DN<8>
  \dqs8_a_t||tdqs8_a_t\  = M_C_CPU0_SA_DQS_DP<8>
  VSS82  = GND
  DQ30_A  = M_C_CPU0_SA_DQ<30>
  VSS83  = GND
  DQ31_A  = M_C_CPU0_SA_DQ<31>
  VSS84  = GND
  CB2_A  = M_C_CPU0_SA_CB<2>
  VSS85  = GND
  CB3_A  = M_C_CPU0_SA_CB<3>
  VSS86  = GND
  \dqs9_a_c||tdqs9_a_c\  = M_C_CPU0_SA_DQS_DN<9>
  \dqs9_a_t||tdqs9_a_t\  = M_C_CPU0_SA_DQS_DP<9>
  VSS87  = GND
  CB6_A  = M_C_CPU0_SA_CB<6>
  VSS88  = GND
  CB7_A  = M_C_CPU0_SA_CB<7>
  VSS89  = GND
  RESET_N  = RST_M_CD_CPU0_FPGA_N
  VSS90  = GND
  CS1_A_N  = M_C_CPU0_SA_CS_N<1>
  VSS91  = GND
  CA1_A  = M_C_CPU0_SA_CA<1>
  VSS92  = GND
  CA3_A  = M_C_CPU0_SA_CA<3>
  VSS93  = GND
  CA5_A  = M_C_CPU0_SA_CA<5>
  VSS94  = GND
  CK_T  = M_C_CPU0_CLK_DP<0>
  CK_C  = M_C_CPU0_CLK_DN<0>
  VSS95  = GND
  RFU4  = TP_CHC_CPU0_DIMM1_FRU_4
  CA1_B  = M_C_CPU0_SB_CA<1>
  VSS96  = GND
  CA3_B  = M_C_CPU0_SB_CA<3>
  VSS97  = GND
  CA5_B  = M_C_CPU0_SB_CA<5>
  VSS98  = GND
  PAR_B  = M_C_CPU0_SB_PAR
  VSS99  = GND
  CS1_B_N  = M_C_CPU0_SB_CS_N<1>
  VSS100  = GND
  RFU5  = TP_CHC_CPU0_DIMM1_FRU_5
  RFU6  = TP_CHC_CPU0_DIMM1_FRU_6
  VSS101  = GND
  CB6_B  = M_C_CPU0_SB_CB<6>
  VSS102  = GND
  CB7_B  = M_C_CPU0_SB_CB<7>
  VSS103  = GND
  DQS4_B_C  = M_C_CPU0_SB_DQS_DN<4>
  DQS4_B_T  = M_C_CPU0_SB_DQS_DP<4>
  VSS104  = GND
  CB2_B  = M_C_CPU0_SB_CB<2>
  VSS105  = GND
  CB3_B  = M_C_CPU0_SB_CB<3>
  VSS106  = GND
  DQ2_B  = M_C_CPU0_SB_DQ<2>
  VSS107  = GND
  DQ3_B  = M_C_CPU0_SB_DQ<3>
  VSS108  = GND
  \dqs5_b_c||tdqs5_b_c\  = M_C_CPU0_SB_DQS_DN<5>
  \dqs5_b_t||tdqs5_b_t\  = M_C_CPU0_SB_DQS_DP<5>
  VSS109  = GND
  DQ6_B  = M_C_CPU0_SB_DQ<6>
  VSS110  = GND
  DQ7_B  = M_C_CPU0_SB_DQ<7>
  VSS111  = GND
  DQ10_B  = M_C_CPU0_SB_DQ<10>
  VSS112  = GND
  DQ11_B  = M_C_CPU0_SB_DQ<11>
  VSS113  = GND
  \dqs6_b_c||tdqs6_b_c\  = M_C_CPU0_SB_DQS_DN<6>
  \dqs6_b_t||tdqs6_b_t\  = M_C_CPU0_SB_DQS_DP<6>
  VSS114  = GND
  DQ14_B  = M_C_CPU0_SB_DQ<14>
  VSS115  = GND
  DQ15_B  = M_C_CPU0_SB_DQ<15>
  VSS116  = GND
  DQ18_B  = M_C_CPU0_SB_DQ<18>
  VSS117  = GND
  DQ19_B  = M_C_CPU0_SB_DQ<19>
  VSS118  = GND
  \dqs7_b_c||tdqs7_b_c\  = M_C_CPU0_SB_DQS_DN<7>
  \dqs7_b_t||tdqs7_b_t\  = M_C_CPU0_SB_DQS_DP<7>
  VSS119  = GND
  DQ22_B  = M_C_CPU0_SB_DQ<22>
  VSS120  = GND
  DQ23_B  = M_C_CPU0_SB_DQ<23>
  VSS121  = GND
  DQ26_B  = M_C_CPU0_SB_DQ<26>
  VSS122  = GND
  DQ27_B  = M_C_CPU0_SB_DQ<27>
  VSS123  = GND
  \dqs8_b_c||tdqs8_b_c\  = M_C_CPU0_SB_DQS_DN<8>
  \dqs8_b_t||tdqs8_b_t\  = M_C_CPU0_SB_DQS_DP<8>
  VSS124  = GND
  DQ30_B  = M_C_CPU0_SB_DQ<30>
  VSS125  = GND
  DQ31_B  = M_C_CPU0_SB_DQ<31>
  VSS126  = GND
  G1  = GND
  G2  = GND
  G3  = GND

(kicad_pcb
	(version 20260206)
	(generator "pcbnew")
	(generator_version "10.0")
	(general
		(thickness 1.6)
		(legacy_teardrops no)
	)
	(paper "A4")
	(title_block
		(title "03242023_DA0F0TMBIJ0_F0T_Motherboard_J_brd_V01_OCP.brd")
		(comment 1 "Grand Teton / footprint 885 of 6105 (J5), pads 183-228 of 291")
	)
	(layers
		(0 "F.Cu" signal "TOP")
		(4 "In1.Cu" signal "GND")
		(6 "In2.Cu" signal "IN1")
		(8 "In3.Cu" signal "GND1")
		(10 "In4.Cu" signal "IN2")
		(12 "In5.Cu" signal "GND2")
		(14 "In6.Cu" signal "IN3")
		(16 "In7.Cu" signal "GND3")
		(18 "In8.Cu" signal "VCC")
		(20 "In9.Cu" signal "VCC1")
		(22 "In10.Cu" signal "GND4")
		(24 "In11.Cu" signal "IN4")
		(26 "In12.Cu" signal "GND5")
		(28 "In13.Cu" signal "IN5")
		(30 "In14.Cu" signal "GND6")
		(32 "In15.Cu" signal "IN6")
		(34 "In16.Cu" signal "GND7")
		(2 "B.Cu" signal "BOTTOM")
		(9 "F.Adhes" user "F.Adhesive")
		(11 "B.Adhes" user "B.Adhesive")
		(13 "F.Paste" user "Package Geometry/Pastemask Top")
		(15 "B.Paste" user "Package Geometry/Pastemask Bottom")
		(5 "F.SilkS" user "Ref Des/Silkscreen Top")
		(7 "B.SilkS" user "Ref Des/Silkscreen Bottom")
		(1 "F.Mask" user "Board Geometry/Soldermask Top")
		(3 "B.Mask" user "Board Geometry/Soldermask Bottom")
		(17 "Dwgs.User" user "User.Drawings")
		(19 "Cmts.User" user "User.Comments")
		(21 "Eco1.User" user "User.Eco1")
		(23 "Eco2.User" user "User.Eco2")
		(25 "Edge.Cuts" user "Board Geometry/Outline")
		(27 "Margin" user)
		(31 "F.CrtYd" user "Package Geometry/Place Bound Top")
		(29 "B.CrtYd" user "Package Geometry/Place Bound Bottom")
		(35 "F.Fab" user "Ref Des/Assembly Top")
		(33 "B.Fab" user "Ref Des/Assembly Bottom")
	)
	(footprint ""
		(layer "F.Cu")
		(at 273.218148 -258.091686)
		(property "Reference" "J5"
			(at -3.683 -81.702148 0)
			(unlocked yes)
			(layer "F.SilkS")
			(effects
				(font
					(size 0.7874 0.5842)
					(thickness 0.1524)
				)
				(justify left)
			)
		)
		(property "Value" ""
			(at 0 0 0)
			(layer "F.Fab")
			(effects
				(font
					(size 1.27 1.27)
				)
			)
		)
		(duplicate_pad_numbers_are_jumpers no)
		(pad "183" smd rect
			(at 2.050034 -31.025084 270)
			(size 0.519938 1.4986)
			(layers "F.Cu" "F.Mask" "F.Paste")
			(net "M_C_CPU0_SA_DQ<23>")
		)
		(pad "184" smd rect
			(at 2.050034 -30.174946 270)
			(size 0.519938 1.4986)
			(layers "F.Cu" "F.Mask" "F.Paste")
			(net "GND")
		)
		(pad "185" smd rect
			(at 2.050034 -29.325062 270)
			(size 0.519938 1.4986)
			(layers "F.Cu" "F.Mask" "F.Paste")
			(net "M_C_CPU0_SA_DQ<26>")
		)
		(pad "186" smd rect
			(at 2.050034 -28.474924 270)
			(size 0.519938 1.4986)
			(layers "F.Cu" "F.Mask" "F.Paste")
			(net "GND")
		)
		(pad "187" smd rect
			(at 2.050034 -27.62504 270)
			(size 0.519938 1.4986)
			(layers "F.Cu" "F.Mask" "F.Paste")
			(net "M_C_CPU0_SA_DQ<27>")
		)
		(pad "188" smd rect
			(at 2.050034 -26.774902 270)
			(size 0.519938 1.4986)
			(layers "F.Cu" "F.Mask" "F.Paste")
			(net "GND")
		)
		(pad "189" smd rect
			(at 2.050034 -25.925018 270)
			(size 0.519938 1.4986)
			(layers "F.Cu" "F.Mask" "F.Paste")
			(net "M_C_CPU0_SA_DQS_DN<8>")
		)
		(pad "190" smd rect
			(at 2.050034 -25.07488 270)
			(size 0.519938 1.4986)
			(layers "F.Cu" "F.Mask" "F.Paste")
			(net "M_C_CPU0_SA_DQS_DP<8>")
		)
		(pad "191" smd rect
			(at 2.050034 -24.224996 270)
			(size 0.519938 1.4986)
			(layers "F.Cu" "F.Mask" "F.Paste")
			(net "GND")
		)
		(pad "192" smd rect
			(at 2.050034 -23.375112 270)
			(size 0.519938 1.4986)
			(layers "F.Cu" "F.Mask" "F.Paste")
			(net "M_C_CPU0_SA_DQ<30>")
		)
		(pad "193" smd rect
			(at 2.050034 -22.524974 270)
			(size 0.519938 1.4986)
			(layers "F.Cu" "F.Mask" "F.Paste")
			(net "GND")
		)
		(pad "194" smd rect
			(at 2.050034 -21.67509 270)
			(size 0.519938 1.4986)
			(layers "F.Cu" "F.Mask" "F.Paste")
			(net "M_C_CPU0_SA_DQ<31>")
		)
		(pad "195" smd rect
			(at 2.050034 -20.824952 270)
			(size 0.519938 1.4986)
			(layers "F.Cu" "F.Mask" "F.Paste")
			(net "GND")
		)
		(pad "196" smd rect
			(at 2.050034 -19.975068 270)
			(size 0.519938 1.4986)
			(layers "F.Cu" "F.Mask" "F.Paste")
			(net "M_C_CPU0_SA_CB<2>")
		)
		(pad "197" smd rect
			(at 2.050034 -19.12493 270)
			(size 0.519938 1.4986)
			(layers "F.Cu" "F.Mask" "F.Paste")
			(net "GND")
		)
		(pad "198" smd rect
			(at 2.050034 -18.275046 270)
			(size 0.519938 1.4986)
			(layers "F.Cu" "F.Mask" "F.Paste")
			(net "M_C_CPU0_SA_CB<3>")
		)
		(pad "199" smd rect
			(at 2.050034 -17.424908 270)
			(size 0.519938 1.4986)
			(layers "F.Cu" "F.Mask" "F.Paste")
			(net "GND")
		)
		(pad "200" smd rect
			(at 2.050034 -16.575024 270)
			(size 0.519938 1.4986)
			(layers "F.Cu" "F.Mask" "F.Paste")
			(net "M_C_CPU0_SA_DQS_DN<9>")
		)
		(pad "201" smd rect
			(at 2.050034 -15.724886 270)
			(size 0.519938 1.4986)
			(layers "F.Cu" "F.Mask" "F.Paste")
			(net "M_C_CPU0_SA_DQS_DP<9>")
		)
		(pad "202" smd rect
			(at 2.050034 -14.875002 270)
			(size 0.519938 1.4986)
			(layers "F.Cu" "F.Mask" "F.Paste")
			(net "GND")
		)
		(pad "203" smd rect
			(at 2.050034 -14.025118 270)
			(size 0.519938 1.4986)
			(layers "F.Cu" "F.Mask" "F.Paste")
			(net "M_C_CPU0_SA_CB<6>")
		)
		(pad "204" smd rect
			(at 2.050034 -13.17498 270)
			(size 0.519938 1.4986)
			(layers "F.Cu" "F.Mask" "F.Paste")
			(net "GND")
		)
		(pad "205" smd rect
			(at 2.050034 -12.325096 270)
			(size 0.519938 1.4986)
			(layers "F.Cu" "F.Mask" "F.Paste")
			(net "M_C_CPU0_SA_CB<7>")
		)
		(pad "206" smd rect
			(at 2.050034 -11.474958 270)
			(size 0.519938 1.4986)
			(layers "F.Cu" "F.Mask" "F.Paste")
			(net "GND")
		)
		(pad "207" smd rect
			(at 2.050034 -10.625074 270)
			(size 0.519938 1.4986)
			(layers "F.Cu" "F.Mask" "F.Paste")
			(net "RST_M_CD_CPU0_FPGA_N")
		)
		(pad "208" smd rect
			(at 2.050034 -9.774936 270)
			(size 0.519938 1.4986)
			(layers "F.Cu" "F.Mask" "F.Paste")
			(net "GND")
		)
		(pad "209" smd rect
			(at 2.050034 -8.925052 270)
			(size 0.519938 1.4986)
			(layers "F.Cu" "F.Mask" "F.Paste")
			(net "M_C_CPU0_SA_CS_N<1>")
		)
		(pad "210" smd rect
			(at 2.050034 -8.074914 270)
			(size 0.519938 1.4986)
			(layers "F.Cu" "F.Mask" "F.Paste")
			(net "GND")
		)
		(pad "211" smd rect
			(at 2.050034 -7.22503 270)
			(size 0.519938 1.4986)
			(layers "F.Cu" "F.Mask" "F.Paste")
			(net "M_C_CPU0_SA_CA<1>")
		)
		(pad "212" smd rect
			(at 2.050034 -6.374892 270)
			(size 0.519938 1.4986)
			(layers "F.Cu" "F.Mask" "F.Paste")
			(net "GND")
		)
		(pad "213" smd rect
			(at 2.050034 -5.525008 270)
			(size 0.519938 1.4986)
			(layers "F.Cu" "F.Mask" "F.Paste")
			(net "M_C_CPU0_SA_CA<3>")
		)
		(pad "214" smd rect
			(at 2.050034 -4.675124 270)
			(size 0.519938 1.4986)
			(layers "F.Cu" "F.Mask" "F.Paste")
			(net "GND")
		)
		(pad "215" smd rect
			(at 2.050034 -3.824986 270)
			(size 0.519938 1.4986)
			(layers "F.Cu" "F.Mask" "F.Paste")
			(net "M_C_CPU0_SA_CA<5>")
		)
		(pad "216" smd rect
			(at 2.050034 -2.975102 270)
			(size 0.519938 1.4986)
			(layers "F.Cu" "F.Mask" "F.Paste")
			(net "GND")
		)
		(pad "217" smd rect
			(at 2.050034 -2.124964 270)
			(size 0.519938 1.4986)
			(layers "F.Cu" "F.Mask" "F.Paste")
			(net "M_C_CPU0_CLK_DP<0>")
		)
		(pad "218" smd rect
			(at 2.050034 -1.27508 270)
			(size 0.519938 1.4986)
			(layers "F.Cu" "F.Mask" "F.Paste")
			(net "M_C_CPU0_CLK_DN<0>")
		)
		(pad "219" smd rect
			(at 2.050034 -0.424942 270)
			(size 0.519938 1.4986)
			(layers "F.Cu" "F.Mask" "F.Paste")
			(net "GND")
		)
		(pad "220" smd rect
			(at 2.050034 5.525008 270)
			(size 0.519938 1.4986)
			(layers "F.Cu" "F.Mask" "F.Paste")
			(net "TP_CHC_CPU0_DIMM1_FRU_4")
		)
		(pad "221" smd rect
			(at 2.050034 6.374892 270)
			(size 0.519938 1.4986)
			(layers "F.Cu" "F.Mask" "F.Paste")
			(net "M_C_CPU0_SB_CA<1>")
		)
		(pad "222" smd rect
			(at 2.050034 7.22503 270)
			(size 0.519938 1.4986)
			(layers "F.Cu" "F.Mask" "F.Paste")
			(net "GND")
		)
		(pad "223" smd rect
			(at 2.050034 8.074914 270)
			(size 0.519938 1.4986)
			(layers "F.Cu" "F.Mask" "F.Paste")
			(net "M_C_CPU0_SB_CA<3>")
		)
		(pad "224" smd rect
			(at 2.050034 8.925052 270)
			(size 0.519938 1.4986)
			(layers "F.Cu" "F.Mask" "F.Paste")
			(net "GND")
		)
		(pad "225" smd rect
			(at 2.050034 9.774936 270)
			(size 0.519938 1.4986)
			(layers "F.Cu" "F.Mask" "F.Paste")
			(net "M_C_CPU0_SB_CA<5>")
		)
		(pad "226" smd rect
			(at 2.050034 10.625074 270)
			(size 0.519938 1.4986)
			(layers "F.Cu" "F.Mask" "F.Paste")
			(net "GND")
		)
		(pad "227" smd rect
			(at 2.050034 11.474958 270)
			(size 0.519938 1.4986)
			(layers "F.Cu" "F.Mask" "F.Paste")
			(net "M_C_CPU0_SB_PAR")
		)
		(pad "228" smd rect
			(at 2.050034 12.325096 270)
			(size 0.519938 1.4986)
			(layers "F.Cu" "F.Mask" "F.Paste")
			(net "GND")
		)
	)
)
